(kicad_pcb
	(version 20260206)
	(generator "pcbnew")
	(generator_version "10.0")
	(general
		(thickness 1.6)
		(legacy_teardrops no)
	)
	(paper "A4")
	(title_block
		(title "03242023_DA0F0TMBIJ0_F0T_Motherboard_J_brd_V01_OCP.brd")
		(comment 1 "Grand Teton / footprints 5459-5464 of 6105")
	)
	(layers
		(0 "F.Cu" signal "TOP")
		(4 "In1.Cu" signal "GND")
		(6 "In2.Cu" signal "IN1")
		(8 "In3.Cu" signal "GND1")
		(10 "In4.Cu" signal "IN2")
		(12 "In5.Cu" signal "GND2")
		(14 "In6.Cu" signal "IN3")
		(16 "In7.Cu" signal "GND3")
		(18 "In8.Cu" signal "VCC")
		(20 "In9.Cu" signal "VCC1")
		(22 "In10.Cu" signal "GND4")
		(24 "In11.Cu" signal "IN4")
		(26 "In12.Cu" signal "GND5")
		(28 "In13.Cu" signal "IN5")
		(30 "In14.Cu" signal "GND6")
		(32 "In15.Cu" signal "IN6")
		(34 "In16.Cu" signal "GND7")
		(2 "B.Cu" signal "BOTTOM")
		(9 "F.Adhes" user "F.Adhesive")
		(11 "B.Adhes" user "B.Adhesive")
		(13 "F.Paste" user "Package Geometry/Pastemask Top")
		(15 "B.Paste" user "Package Geometry/Pastemask Bottom")
		(5 "F.SilkS" user "Ref Des/Silkscreen Top")
		(7 "B.SilkS" user "Ref Des/Silkscreen Bottom")
		(1 "F.Mask" user "Board Geometry/Soldermask Top")
		(3 "B.Mask" user "Board Geometry/Soldermask Bottom")
		(17 "Dwgs.User" user "User.Drawings")
		(19 "Cmts.User" user "User.Comments")
		(21 "Eco1.User" user "User.Eco1")
		(23 "Eco2.User" user "User.Eco2")
		(25 "Edge.Cuts" user "Board Geometry/Outline")
		(27 "Margin" user)
		(31 "F.CrtYd" user "Package Geometry/Place Bound Top")
		(29 "B.CrtYd" user "Package Geometry/Place Bound Bottom")
		(35 "F.Fab" user "Ref Des/Assembly Top")
		(33 "B.Fab" user "Ref Des/Assembly Bottom")
	)
	(footprint ""
		(layer "B.Cu")
		(at 293.812214 -321.549776 -90)
		(property "Reference" "C12"
			(at 0 0 90)
			(layer "B.SilkS")
			(hide yes)
			(effects
				(font
					(size 1.27 1.27)
				)
				(justify mirror)
			)
		)
		(property "Value" ""
			(at 0 0 90)
			(layer "B.Fab")
			(effects
				(font
					(size 1.27 1.27)
				)
				(justify mirror)
			)
		)
		(duplicate_pad_numbers_are_jumpers no)
		(fp_line
			(start -1.524 0.762)
			(end 1.524 0.762)
			(stroke
				(width 0.1524)
				(type default)
			)
			(layer "B.SilkS")
		)
		(fp_line
			(start 1.524 0.762)
			(end 1.524 -0.762)
			(stroke
				(width 0.1524)
				(type default)
			)
			(layer "B.SilkS")
		)
		(fp_line
			(start -1.524 -0.762)
			(end -1.524 0.762)
			(stroke
				(width 0.1524)
				(type default)
			)
			(layer "B.SilkS")
		)
		(fp_line
			(start 1.524 -0.762)
			(end -1.524 -0.762)
			(stroke
				(width 0.1524)
				(type default)
			)
			(layer "B.SilkS")
		)
		(fp_line
			(start -1.1049 0.724916)
			(end -1.1049 -0.724916)
			(stroke
				(width 0.1)
				(type default)
			)
			(layer "B.Fab")
		)
		(fp_line
			(start 1.1049 0.724916)
			(end -1.1049 0.724916)
			(stroke
				(width 0.1)
				(type default)
			)
			(layer "B.Fab")
		)
		(fp_line
			(start -1.1049 -0.724916)
			(end 1.1049 -0.724916)
			(stroke
				(width 0.1)
				(type default)
			)
			(layer "B.Fab")
		)
		(fp_line
			(start 1.1049 -0.724916)
			(end 1.1049 0.724916)
			(stroke
				(width 0.1)
				(type default)
			)
			(layer "B.Fab")
		)
		(pad "1" smd rect
			(at 0.889 0 270)
			(size 1.016 1.27)
			(layers "B.Cu" "B.Mask" "B.Paste")
			(net "P12V_S3_AUX_CPU0_NVDIMM")
		)
		(pad "2" smd rect
			(at -0.889 0 270)
			(size 1.016 1.27)
			(layers "B.Cu" "B.Mask" "B.Paste")
			(net "GND")
		)
	)
	(footprint ""
		(layer "B.Cu")
		(at 31.94304 -166.25316 90)
		(property "Reference" "PC814"
			(at 0 0 90)
			(layer "B.SilkS")
			(hide yes)
			(effects
				(font
					(size 1.27 1.27)
				)
				(justify mirror)
			)
		)
		(property "Value" ""
			(at 0 0 90)
			(layer "B.Fab")
			(effects
				(font
					(size 1.27 1.27)
				)
				(justify mirror)
			)
		)
		(duplicate_pad_numbers_are_jumpers no)
		(fp_line
			(start 0.7874 -0.4064)
			(end -0.7874 -0.4064)
			(stroke
				(width 0.1524)
				(type default)
			)
			(layer "B.SilkS")
		)
		(fp_line
			(start -0.7874 -0.4064)
			(end -0.7874 0.4064)
			(stroke
				(width 0.1524)
				(type default)
			)
			(layer "B.SilkS")
		)
		(fp_line
			(start 0.7874 0.4064)
			(end 0.7874 -0.4064)
			(stroke
				(width 0.1524)
				(type default)
			)
			(layer "B.SilkS")
		)
		(fp_line
			(start -0.7874 0.4064)
			(end 0.7874 0.4064)
			(stroke
				(width 0.1524)
				(type default)
			)
			(layer "B.SilkS")
		)
		(fp_line
			(start 0.67945 -0.305054)
			(end 0.12065 -0.305054)
			(stroke
				(width 0.1)
				(type default)
			)
			(layer "B.Fab")
		)
		(fp_line
			(start 0.12065 -0.305054)
			(end 0.12065 -0.2794)
			(stroke
				(width 0.1)
				(type default)
			)
			(layer "B.Fab")
		)
		(fp_line
			(start -0.12065 -0.3048)
			(end -0.67945 -0.3048)
			(stroke
				(width 0.1)
				(type default)
			)
			(layer "B.Fab")
		)
		(fp_line
			(start -0.67945 -0.3048)
			(end -0.67945 0.3048)
			(stroke
				(width 0.1)
				(type default)
			)
			(layer "B.Fab")
		)
		(fp_line
			(start 0.12065 -0.2794)
			(end -0.12065 -0.2794)
			(stroke
				(width 0.1)
				(type default)
			)
			(layer "B.Fab")
		)
		(fp_line
			(start -0.12065 -0.2794)
			(end -0.12065 -0.3048)
			(stroke
				(width 0.1)
				(type default)
			)
			(layer "B.Fab")
		)
		(fp_line
			(start 0.12065 0.2794)
			(end 0.12065 0.3048)
			(stroke
				(width 0.1)
				(type default)
			)
			(layer "B.Fab")
		)
		(fp_line
			(start -0.120396 0.2794)
			(end 0.12065 0.2794)
			(stroke
				(width 0.1)
				(type default)
			)
			(layer "B.Fab")
		)
		(fp_line
			(start 0.67945 0.3048)
			(end 0.67945 -0.305054)
			(stroke
				(width 0.1)
				(type default)
			)
			(layer "B.Fab")
		)
		(fp_line
			(start 0.12065 0.3048)
			(end 0.67945 0.3048)
			(stroke
				(width 0.1)
				(type default)
			)
			(layer "B.Fab")
		)
		(fp_line
			(start -0.120396 0.3048)
			(end -0.120396 0.2794)
			(stroke
				(width 0.1)
				(type default)
			)
			(layer "B.Fab")
		)
		(fp_line
			(start -0.67945 0.3048)
			(end -0.120396 0.3048)
			(stroke
				(width 0.1)
				(type default)
			)
			(layer "B.Fab")
		)
		(pad "1" smd circle
			(at 0.40005 0 270)
			(size 0 0)
			(layers "B.Cu" "B.Mask" "B.Paste")
			(net "PVCCD_HV_CPU1_ISENSE_N")
		)
		(pad "2" smd circle
			(at -0.40005 0 270)
			(size 0 0)
			(layers "B.Cu" "B.Mask" "B.Paste")
			(net "PVCCD_HV_CPU1_ISENSE_P")
		)
	)
	(footprint ""
		(layer "B.Cu")
		(at 434.00472 -44.1325 -90)
		(property "Reference" "R4679"
			(at 0 0 90)
			(layer "B.SilkS")
			(hide yes)
			(effects
				(font
					(size 1.27 1.27)
				)
				(justify mirror)
			)
		)
		(property "Value" ""
			(at 0 0 90)
			(layer "B.Fab")
			(effects
				(font
					(size 1.27 1.27)
				)
				(justify mirror)
			)
		)
		(duplicate_pad_numbers_are_jumpers no)
		(fp_line
			(start -0.7874 0.4064)
			(end 0.7874 0.4064)
			(stroke
				(width 0.1524)
				(type default)
			)
			(layer "B.SilkS")
		)
		(fp_line
			(start 0.7874 0.4064)
			(end 0.7874 -0.4064)
			(stroke
				(width 0.1524)
				(type default)
			)
			(layer "B.SilkS")
		)
		(fp_line
			(start -0.7874 -0.4064)
			(end -0.7874 0.4064)
			(stroke
				(width 0.1524)
				(type default)
			)
			(layer "B.SilkS")
		)
		(fp_line
			(start 0.7874 -0.4064)
			(end -0.7874 -0.4064)
			(stroke
				(width 0.1524)
				(type default)
			)
			(layer "B.SilkS")
		)
		(fp_line
			(start -0.67945 0.3048)
			(end -0.120396 0.3048)
			(stroke
				(width 0.1)
				(type default)
			)
			(layer "B.Fab")
		)
		(fp_line
			(start -0.120396 0.3048)
			(end -0.120396 0.2794)
			(stroke
				(width 0.1)
				(type default)
			)
			(layer "B.Fab")
		)
		(fp_line
			(start 0.12065 0.3048)
			(end 0.67945 0.3048)
			(stroke
				(width 0.1)
				(type default)
			)
			(layer "B.Fab")
		)
		(fp_line
			(start 0.67945 0.3048)
			(end 0.67945 -0.305054)
			(stroke
				(width 0.1)
				(type default)
			)
			(layer "B.Fab")
		)
		(fp_line
			(start -0.120396 0.2794)
			(end 0.12065 0.2794)
			(stroke
				(width 0.1)
				(type default)
			)
			(layer "B.Fab")
		)
		(fp_line
			(start 0.12065 0.2794)
			(end 0.12065 0.3048)
			(stroke
				(width 0.1)
				(type default)
			)
			(layer "B.Fab")
		)
		(fp_line
			(start -0.12065 -0.2794)
			(end -0.12065 -0.3048)
			(stroke
				(width 0.1)
				(type default)
			)
			(layer "B.Fab")
		)
		(fp_line
			(start 0.12065 -0.2794)
			(end -0.12065 -0.2794)
			(stroke
				(width 0.1)
				(type default)
			)
			(layer "B.Fab")
		)
		(fp_line
			(start -0.67945 -0.3048)
			(end -0.67945 0.3048)
			(stroke
				(width 0.1)
				(type default)
			)
			(layer "B.Fab")
		)
		(fp_line
			(start -0.12065 -0.3048)
			(end -0.67945 -0.3048)
			(stroke
				(width 0.1)
				(type default)
			)
			(layer "B.Fab")
		)
		(fp_line
			(start 0.12065 -0.305054)
			(end 0.12065 -0.2794)
			(stroke
				(width 0.1)
				(type default)
			)
			(layer "B.Fab")
		)
		(fp_line
			(start 0.67945 -0.305054)
			(end 0.12065 -0.305054)
			(stroke
				(width 0.1)
				(type default)
			)
			(layer "B.Fab")
		)
		(pad "1" smd circle
			(at 0.40005 0 90)
			(size 0 0)
			(layers "B.Cu" "B.Mask" "B.Paste")
			(net "P5V")
		)
		(pad "2" smd circle
			(at -0.40005 0 90)
			(size 0 0)
			(layers "B.Cu" "B.Mask" "B.Paste")
			(net "PWRGD_P5V")
		)
	)
	(footprint ""
		(layer "B.Cu")
		(at 316.55004 -193.53911 90)
		(property "Reference" "R340"
			(at 0 0 90)
			(layer "B.SilkS")
			(hide yes)
			(effects
				(font
					(size 1.27 1.27)
				)
				(justify mirror)
			)
		)
		(property "Value" ""
			(at 0 0 90)
			(layer "B.Fab")
			(effects
				(font
					(size 1.27 1.27)
				)
				(justify mirror)
			)
		)
		(duplicate_pad_numbers_are_jumpers no)
		(fp_line
			(start 0.7874 -0.4064)
			(end -0.7874 -0.4064)
			(stroke
				(width 0.1524)
				(type default)
			)
			(layer "B.SilkS")
		)
		(fp_line
			(start -0.7874 -0.4064)
			(end -0.7874 0.4064)
			(stroke
				(width 0.1524)
				(type default)
			)
			(layer "B.SilkS")
		)
		(fp_line
			(start 0.7874 0.4064)
			(end 0.7874 -0.4064)
			(stroke
				(width 0.1524)
				(type default)
			)
			(layer "B.SilkS")
		)
		(fp_line
			(start -0.7874 0.4064)
			(end 0.7874 0.4064)
			(stroke
				(width 0.1524)
				(type default)
			)
			(layer "B.SilkS")
		)
		(fp_line
			(start 0.67945 -0.305054)
			(end 0.12065 -0.305054)
			(stroke
				(width 0.1)
				(type default)
			)
			(layer "B.Fab")
		)
		(fp_line
			(start 0.12065 -0.305054)
			(end 0.12065 -0.2794)
			(stroke
				(width 0.1)
				(type default)
			)
			(layer "B.Fab")
		)
		(fp_line
			(start -0.12065 -0.3048)
			(end -0.67945 -0.3048)
			(stroke
				(width 0.1)
				(type default)
			)
			(layer "B.Fab")
		)
		(fp_line
			(start -0.67945 -0.3048)
			(end -0.67945 0.3048)
			(stroke
				(width 0.1)
				(type default)
			)
			(layer "B.Fab")
		)
		(fp_line
			(start 0.12065 -0.2794)
			(end -0.12065 -0.2794)
			(stroke
				(width 0.1)
				(type default)
			)
			(layer "B.Fab")
		)
		(fp_line
			(start -0.12065 -0.2794)
			(end -0.12065 -0.3048)
			(stroke
				(width 0.1)
				(type default)
			)
			(layer "B.Fab")
		)
		(fp_line
			(start 0.12065 0.2794)
			(end 0.12065 0.3048)
			(stroke
				(width 0.1)
				(type default)
			)
			(layer "B.Fab")
		)
		(fp_line
			(start -0.120396 0.2794)
			(end 0.12065 0.2794)
			(stroke
				(width 0.1)
				(type default)
			)
			(layer "B.Fab")
		)
		(fp_line
			(start 0.67945 0.3048)
			(end 0.67945 -0.305054)
			(stroke
				(width 0.1)
				(type default)
			)
			(layer "B.Fab")
		)
		(fp_line
			(start 0.12065 0.3048)
			(end 0.67945 0.3048)
			(stroke
				(width 0.1)
				(type default)
			)
			(layer "B.Fab")
		)
		(fp_line
			(start -0.120396 0.3048)
			(end -0.120396 0.2794)
			(stroke
				(width 0.1)
				(type default)
			)
			(layer "B.Fab")
		)
		(fp_line
			(start -0.67945 0.3048)
			(end -0.120396 0.3048)
			(stroke
				(width 0.1)
				(type default)
			)
			(layer "B.Fab")
		)
		(pad "1" smd circle
			(at 0.40005 0 270)
			(size 0 0)
			(layers "B.Cu" "B.Mask" "B.Paste")
			(net "H_CPU0_ERR1_LVC1_R_N")
		)
		(pad "2" smd circle
			(at -0.40005 0 270)
			(size 0 0)
			(layers "B.Cu" "B.Mask" "B.Paste")
			(net "H_CPU_ERR1_LVC1_R_N")
		)
	)
	(footprint ""
		(layer "B.Cu")
		(at 178.1556 -115.775486 90)
		(property "Reference" "C1927"
			(at 0 0 90)
			(layer "B.SilkS")
			(hide yes)
			(effects
				(font
					(size 1.27 1.27)
				)
				(justify mirror)
			)
		)
		(property "Value" ""
			(at 0 0 90)
			(layer "B.Fab")
			(effects
				(font
					(size 1.27 1.27)
				)
				(justify mirror)
			)
		)
		(duplicate_pad_numbers_are_jumpers no)
		(fp_line
			(start 0.69215 -0.2921)
			(end -0.69215 -0.2921)
			(stroke
				(width 0.1524)
				(type default)
			)
			(layer "B.SilkS")
		)
		(fp_line
			(start -0.69215 -0.2921)
			(end -0.69215 0.2921)
			(stroke
				(width 0.1524)
				(type default)
			)
			(layer "B.SilkS")
		)
		(fp_line
			(start 0.69215 0.2921)
			(end 0.69215 -0.2921)
			(stroke
				(width 0.1524)
				(type default)
			)
			(layer "B.SilkS")
		)
		(fp_line
			(start -0.69215 0.2921)
			(end 0.69215 0.2921)
			(stroke
				(width 0.1524)
				(type default)
			)
			(layer "B.SilkS")
		)
		(fp_line
			(start 0.51435 -0.2794)
			(end -0.51435 -0.2794)
			(stroke
				(width 0.1)
				(type default)
			)
			(layer "B.Fab")
		)
		(fp_line
			(start -0.51435 -0.2794)
			(end -0.51435 0.2794)
			(stroke
				(width 0.1)
				(type default)
			)
			(layer "B.Fab")
		)
		(fp_line
			(start 0.51435 0.2794)
			(end 0.51435 -0.2794)
			(stroke
				(width 0.1)
				(type default)
			)
			(layer "B.Fab")
		)
		(fp_line
			(start -0.51435 0.2794)
			(end 0.51435 0.2794)
			(stroke
				(width 0.1)
				(type default)
			)
			(layer "B.Fab")
		)
		(pad "1" smd circle
			(at 0.40005 0 270)
			(size 0 0)
			(layers "B.Cu" "B.Mask" "B.Paste")
			(net "P3V3_AUX_FPGA_VCCIO1")
		)
		(pad "2" smd circle
			(at -0.40005 0 270)
			(size 0 0)
			(layers "B.Cu" "B.Mask" "B.Paste")
			(net "GND")
		)
		(zone
			(layer "B.Cu")
			(hatch none 0.5)
			(connect_pads
				(clearance 0)
			)
			(min_thickness 0.25)
			(keepout
				(tracks not_allowed)
				(vias allowed)
				(pads allowed)
				(copperpour not_allowed)
				(footprints allowed)
			)
			(placement
				(enabled no)
				(sheetname "")
			)
			(fill
				(thermal_gap 0.5)
				(thermal_bridge_width 0.5)
				(island_removal_mode 0)
			)
			(polygon
				(pts
					(xy 178.24323 -115.965986) (xy 178.301396 -115.874546) (xy 178.301396 -115.675156) (xy 178.24323 -115.584986)
					(xy 178.06797 -115.584986) (xy 178.00955 -115.675156) (xy 178.00955 -115.874546) (xy 178.067716 -115.965986)
				)
			)
		)
	)
	(footprint ""
		(layer "B.Cu")
		(at 160.83788 -109.489748)
		(property "Reference" "R1440"
			(at 0 0 0)
			(layer "B.SilkS")
			(hide yes)
			(effects
				(font
					(size 1.27 1.27)
				)
				(justify mirror)
			)
		)
		(property "Value" ""
			(at 0 0 0)
			(layer "B.Fab")
			(effects
				(font
					(size 1.27 1.27)
				)
				(justify mirror)
			)
		)
		(duplicate_pad_numbers_are_jumpers no)
		(fp_line
			(start -0.7874 -0.4064)
			(end -0.7874 0.4064)
			(stroke
				(width 0.1524)
				(type default)
			)
			(layer "B.SilkS")
		)
		(fp_line
			(start -0.7874 0.4064)
			(end 0.7874 0.4064)
			(stroke
				(width 0.1524)
				(type default)
			)
			(layer "B.SilkS")
		)
		(fp_line
			(start 0.7874 -0.4064)
			(end -0.7874 -0.4064)
			(stroke
				(width 0.1524)
				(type default)
			)
			(layer "B.SilkS")
		)
		(fp_line
			(start 0.7874 0.4064)
			(end 0.7874 -0.4064)
			(stroke
				(width 0.1524)
				(type default)
			)
			(layer "B.SilkS")
		)
		(fp_line
			(start -0.67945 -0.3048)
			(end -0.67945 0.3048)
			(stroke
				(width 0.1)
				(type default)
			)
			(layer "B.Fab")
		)
		(fp_line
			(start -0.67945 0.3048)
			(end -0.120396 0.3048)
			(stroke
				(width 0.1)
				(type default)
			)
			(layer "B.Fab")
		)
		(fp_line
			(start -0.12065 -0.3048)
			(end -0.67945 -0.3048)
			(stroke
				(width 0.1)
				(type default)
			)
			(layer "B.Fab")
		)
		(fp_line
			(start -0.12065 -0.2794)
			(end -0.12065 -0.3048)
			(stroke
				(width 0.1)
				(type default)
			)
			(layer "B.Fab")
		)
		(fp_line
			(start -0.120396 0.2794)
			(end 0.12065 0.2794)
			(stroke
				(width 0.1)
				(type default)
			)
			(layer "B.Fab")
		)
		(fp_line
			(start -0.120396 0.3048)
			(end -0.120396 0.2794)
			(stroke
				(width 0.1)
				(type default)
			)
			(layer "B.Fab")
		)
		(fp_line
			(start 0.12065 -0.305054)
			(end 0.12065 -0.2794)
			(stroke
				(width 0.1)
				(type default)
			)
			(layer "B.Fab")
		)
		(fp_line
			(start 0.12065 -0.2794)
			(end -0.12065 -0.2794)
			(stroke
				(width 0.1)
				(type default)
			)
			(layer "B.Fab")
		)
		(fp_line
			(start 0.12065 0.2794)
			(end 0.12065 0.3048)
			(stroke
				(width 0.1)
				(type default)
			)
			(layer "B.Fab")
		)
		(fp_line
			(start 0.12065 0.3048)
			(end 0.67945 0.3048)
			(stroke
				(width 0.1)
				(type default)
			)
			(layer "B.Fab")
		)
		(fp_line
			(start 0.67945 -0.305054)
			(end 0.12065 -0.305054)
			(stroke
				(width 0.1)
				(type default)
			)
			(layer "B.Fab")
		)
		(fp_line
			(start 0.67945 0.3048)
			(end 0.67945 -0.305054)
			(stroke
				(width 0.1)
				(type default)
			)
			(layer "B.Fab")
		)
		(pad "1" smd circle
			(at 0.40005 0 180)
			(size 0 0)
			(layers "B.Cu" "B.Mask" "B.Paste")
			(net "JTAG_PLD_TDO_R")
		)
		(pad "2" smd circle
			(at -0.40005 0 180)
			(size 0 0)
			(layers "B.Cu" "B.Mask" "B.Paste")
			(net "P3V3_AUX")
		)
	)
)
